(kicad_pcb
	(version 20260206)
	(generator "pcbnew")
	(generator_version "10.0")
	(general
		(thickness 1.6)
		(legacy_teardrops no)
	)
	(paper "A4")
	(title_block
		(title "Wiwynn_Tioga_Pass_MB.brd")
		(comment 1 "Tioga Pass / footprints 2253-2253 of 4770")
	)
	(layers
		(0 "F.Cu" signal "TOP")
		(4 "In1.Cu" signal "L2GND")
		(6 "In2.Cu" signal "L3")
		(8 "In3.Cu" signal "L4GND")
		(10 "In4.Cu" signal "L5")
		(12 "In5.Cu" signal "L6GND")
		(14 "In6.Cu" signal "L7VCC")
		(16 "In7.Cu" signal "L8VCC")
		(18 "In8.Cu" signal "L9GND")
		(20 "In9.Cu" signal "L10")
		(22 "In10.Cu" signal "L11GND")
		(24 "In11.Cu" signal "L12")
		(26 "In12.Cu" signal "L13GND")
		(2 "B.Cu" signal "BOTTOM")
		(9 "F.Adhes" user "F.Adhesive")
		(11 "B.Adhes" user "B.Adhesive")
		(13 "F.Paste" user "Package Geometry/Pastemask Top")
		(15 "B.Paste" user "Package Geometry/Pastemask Bottom")
		(5 "F.SilkS" user "Ref Des/Silkscreen Top")
		(7 "B.SilkS" user "Ref Des/Silkscreen Bottom")
		(1 "F.Mask" user "Board Geometry/Soldermask Top")
		(3 "B.Mask" user "Board Geometry/Soldermask Bottom")
		(17 "Dwgs.User" user "User.Drawings")
		(19 "Cmts.User" user "User.Comments")
		(21 "Eco1.User" user "User.Eco1")
		(23 "Eco2.User" user "User.Eco2")
		(25 "Edge.Cuts" user "Board Geometry/Outline")
		(27 "Margin" user)
		(31 "F.CrtYd" user "Package Geometry/Place Bound Top")
		(29 "B.CrtYd" user "Package Geometry/Place Bound Bottom")
		(35 "F.Fab" user "Ref Des/Assembly Top")
		(33 "B.Fab" user "Ref Des/Assembly Bottom")
	)
	(footprint ""
		(layer "F.Cu")
		(at 380.74219 -37.22751)
		(property "Reference" "R8F34"
			(at 0 0 0)
			(layer "F.SilkS")
			(hide yes)
			(effects
				(font
					(size 1.27 1.27)
				)
			)
		)
		(property "Value" ""
			(at 0 0 0)
			(layer "F.Fab")
			(effects
				(font
					(size 1.27 1.27)
				)
			)
		)
		(duplicate_pad_numbers_are_jumpers no)
		(fp_poly
			(pts
				(xy -0.2794 -0.1016) (xy 0.2794 -0.1016) (xy 0.2794 0.9906) (xy -0.2794 0.9906)
			)
			(stroke
				(width 0)
				(type default)
			)
			(fill no)
			(layer "F.CrtYd")
		)
		(fp_line
			(start -0.2794 -0.1016)
			(end -0.2794 0.9906)
			(stroke
				(width 0.1)
				(type default)
			)
			(layer "F.Fab")
		)
		(fp_line
			(start -0.2794 0.9906)
			(end 0.2794 0.9906)
			(stroke
				(width 0.1)
				(type default)
			)
			(layer "F.Fab")
		)
		(fp_line
			(start 0.2794 -0.1016)
			(end -0.2794 -0.1016)
			(stroke
				(width 0.1)
				(type default)
			)
			(layer "F.Fab")
		)
		(fp_line
			(start 0.2794 0.9906)
			(end 0.2794 -0.1016)
			(stroke
				(width 0.1)
				(type default)
			)
			(layer "F.Fab")
		)
		(pad "1" smd rect
			(at 0 0)
			(size 0.508 0.508)
			(layers "F.Cu" "F.Mask" "F.Paste")
			(net "P3V3_STBY")
		)
		(pad "2" smd rect
			(at 0 0.889)
			(size 0.508 0.508)
			(layers "F.Cu" "F.Mask" "F.Paste")
			(net "PU_SPI_BMC_BT_WP_N")
		)
		(zone
			(layer "F.Cu")
			(hatch none 0.5)
			(connect_pads
				(clearance 0)
			)
			(min_thickness 0.25)
			(keepout
				(tracks allowed)
				(vias not_allowed)
				(pads allowed)
				(copperpour not_allowed)
				(footprints allowed)
			)
			(placement
				(enabled no)
				(sheetname "")
			)
			(fill
				(thermal_gap 0.5)
				(thermal_bridge_width 0.5)
				(island_removal_mode 0)
			)
			(polygon
				(pts
					(xy 380.48819 -36.97351) (xy 380.99619 -36.97351) (xy 380.99619 -36.59251) (xy 380.48819 -36.59251)
				)
			)
		)
		(zone
			(layer "F.Cu")
			(hatch none 0.5)
			(connect_pads
				(clearance 0)
			)
			(min_thickness 0.25)
			(keepout
				(tracks not_allowed)
				(vias allowed)
				(pads allowed)
				(copperpour not_allowed)
				(footprints allowed)
			)
			(placement
				(enabled no)
				(sheetname "")
			)
			(fill
				(thermal_gap 0.5)
				(thermal_bridge_width 0.5)
				(island_removal_mode 0)
			)
			(polygon
				(pts
					(xy 380.48819 -36.59251) (xy 380.99619 -36.59251) (xy 380.99619 -36.97351) (xy 380.48819 -36.97351)
				)
			)
		)
	)
)
